(kicad_pcb
	(version 20211014)
	(generator pcbnew)
	(general
    (thickness 1.6)
  )
	(paper "A4")
	(title_block
    (title "SA800U (Snapdragon 845) Baseboard")
    (date "2023-10-19")
    (rev "1.0.3")
    (company "Antmicro Ltd.")
    (comment 1 "www.antmicro.com")
		(comment 9 "footprints 313-321 of 589")
	)
	(layers
    (0 "F.Cu" signal)
    (1 "In1.Cu" power)
    (2 "In2.Cu" signal)
    (3 "In3.Cu" signal)
    (4 "In4.Cu" power)
    (31 "B.Cu" signal)
    (32 "B.Adhes" user "B.Adhesive")
    (33 "F.Adhes" user "F.Adhesive")
    (34 "B.Paste" user)
    (35 "F.Paste" user)
    (36 "B.SilkS" user "B.Silkscreen")
    (37 "F.SilkS" user "F.Silkscreen")
    (38 "B.Mask" user)
    (39 "F.Mask" user)
    (40 "Dwgs.User" user "User.Drawings")
    (41 "Cmts.User" user "User.Comments")
    (42 "Eco1.User" user "User.Eco1")
    (43 "Eco2.User" user "User.Eco2")
    (44 "Edge.Cuts" user)
    (45 "Margin" user)
    (46 "B.CrtYd" user "B.Courtyard")
    (47 "F.CrtYd" user "F.Courtyard")
    (48 "B.Fab" user)
    (49 "F.Fab" user)
  )
	(footprint "sa800u-baseboard-hw-footprints:R_0402_1005Metric" (layer "B.Cu")
    (tedit 5FD9C158)
    (at 136.1 107.15)
    (descr "Resistor SMD 0402")
    (tags "resistor SMD 0402")
    (property "Author" "Antmicro")
    (property "License" "Apache-2.0")
    (property "MPN" "CR0402-FX-2001GLF")
    (property "Manufacturer" "Bourns")
    (property "Sheetfile" "hdmi-converter.kicad_sch")
    (property "Sheetname" "HDMI converter")
    (property "Tolerance" "1%")
    (property "Val" "2k")
    (attr smd)
    (fp_text reference "R44" (at 1.05 2.35 180) (layer "B.SilkS")
      (effects (font (size 0.7 0.7) (thickness 0.15)) (justify left bottom mirror))
    )
    (fp_text value "R_2k_0402" (at 0 -1.4 180) (layer "B.Fab")
      (effects (font (size 0.7 0.7) (thickness 0.15)) (justify left bottom mirror))
    )
    (fp_text user "Author: Antmicro" (at -0.95 -4.169 180) (layer "B.Fab") hide
      (effects (font (size 0.7 0.7) (thickness 0.15)) (justify left bottom mirror))
    )
    (fp_text user "License: Apache-2.0" (at -0.95 -5.169 180) (layer "B.Fab") hide
      (effects (font (size 0.7 0.7) (thickness 0.15)) (justify left bottom mirror))
    )
    (fp_text user "${REFERENCE}" (at -0.95 -3.168 180) (layer "B.Fab") hide
      (effects (font (size 0.7 0.7) (thickness 0.15)) (justify left bottom mirror))
    )
    (fp_rect (start -0.93 0.47) (end 0.93 -0.47) (layer "B.CrtYd") (width 0.05) (fill none))
    (fp_rect (start -0.5 0.25) (end 0.5 -0.25) (layer "B.Fab") (width 0.15) (fill none))
    (pad "1" smd roundrect (at -0.485 0) (size 0.59 0.64) (layers "B.Cu" "B.Paste" "B.Mask") (roundrect_rratio 0.25)
      (net 287 "/HDMI converter/LT9611_SCL") (pintype "passive"))
    (pad "2" smd roundrect (at 0.485 0) (size 0.59 0.64) (layers "B.Cu" "B.Paste" "B.Mask") (roundrect_rratio 0.25)
      (net 131 "3V3_SYS") (pintype "passive"))
  )
	(footprint "sa800u-baseboard-hw-footprints:R_0402_1005Metric" (layer "B.Cu")
    (tedit 5FD9C158)
    (at 136.1 108.15)
    (descr "Resistor SMD 0402")
    (tags "resistor SMD 0402")
    (property "Author" "Antmicro")
    (property "License" "Apache-2.0")
    (property "MPN" "CR0402-FX-2001GLF")
    (property "Manufacturer" "Bourns")
    (property "Sheetfile" "hdmi-converter.kicad_sch")
    (property "Sheetname" "HDMI converter")
    (property "Tolerance" "1%")
    (property "Val" "2k")
    (attr smd)
    (fp_text reference "R46" (at 1.05 2.35 180) (layer "B.SilkS")
      (effects (font (size 0.7 0.7) (thickness 0.15)) (justify left bottom mirror))
    )
    (fp_text value "R_2k_0402" (at 0 -1.4 180) (layer "B.Fab")
      (effects (font (size 0.7 0.7) (thickness 0.15)) (justify left bottom mirror))
    )
    (fp_text user "License: Apache-2.0" (at -0.95 -5.169 180) (layer "B.Fab") hide
      (effects (font (size 0.7 0.7) (thickness 0.15)) (justify left bottom mirror))
    )
    (fp_text user "Author: Antmicro" (at -0.95 -4.169 180) (layer "B.Fab") hide
      (effects (font (size 0.7 0.7) (thickness 0.15)) (justify left bottom mirror))
    )
    (fp_text user "${REFERENCE}" (at -0.95 -3.168 180) (layer "B.Fab") hide
      (effects (font (size 0.7 0.7) (thickness 0.15)) (justify left bottom mirror))
    )
    (fp_rect (start -0.93 0.47) (end 0.93 -0.47) (layer "B.CrtYd") (width 0.05) (fill none))
    (fp_rect (start -0.5 0.25) (end 0.5 -0.25) (layer "B.Fab") (width 0.15) (fill none))
    (pad "1" smd roundrect (at -0.485 0) (size 0.59 0.64) (layers "B.Cu" "B.Paste" "B.Mask") (roundrect_rratio 0.25)
      (net 288 "/HDMI converter/LT9611_SDA") (pintype "passive"))
    (pad "2" smd roundrect (at 0.485 0) (size 0.59 0.64) (layers "B.Cu" "B.Paste" "B.Mask") (roundrect_rratio 0.25)
      (net 131 "3V3_SYS") (pintype "passive"))
  )
	(footprint "sa800u-baseboard-hw-footprints:Spacer_SMD_M2.5_H6mm_Wurth_9774060151" (layer "B.Cu")
    (tedit 61168484)
    (at 151.5 85.5)
    (property "Author" "Antmicro")
    (property "License" "Apache-2.0")
    (property "MPN" "9774060151")
    (property "Manufacturer" "Würth Elektronik")
    (property "Sheetfile" "sa800u-baseboard-hw.kicad_sch")
    (property "Sheetname" "")
    (attr smd)
    (fp_text reference "SP1" (at -3.09 0.43 180) (layer "B.SilkS")
      (effects (font (size 0.7 0.7) (thickness 0.15)) (justify left bottom mirror))
    )
    (fp_text value "Spacer_H6mm_9774060151" (at -2.575 -4 180) (layer "B.Fab")
      (effects (font (size 0.7 0.7) (thickness 0.15)) (justify left bottom mirror))
    )
    (fp_text user "Author: Antmicro" (at -2.551 -6.5 180) (layer "B.Fab") hide
      (effects (font (size 0.7 0.7) (thickness 0.15)) (justify left bottom mirror))
    )
    (fp_text user "License: Apache-2.0" (at -2.551 -7.75 180) (layer "B.Fab") hide
      (effects (font (size 0.7 0.7) (thickness 0.15)) (justify left bottom mirror))
    )
    (fp_text user "${REFERENCE}" (at -2.551 -5.25 180) (layer "B.Fab") hide
      (effects (font (size 0.7 0.7) (thickness 0.15)) (justify left bottom mirror))
    )
    (fp_circle (center 0 0) (end 2.522481 0) (layer "B.Paste") (width 0.8) (fill none))
    (fp_circle (center -0.001 0) (end 2.548 0) (layer "B.Fab") (width 0.15) (fill none))
    (pad "1" smd circle (at 0 0) (size 6 6) (layers "B.Cu" "B.Mask")
      (net 392 "Net-(R1-Pad2)") (pintype "passive"))
    (pad "1" thru_hole circle (at -0.001 0) (size 4.1 4.1) (drill 3.7) (layers *.Cu *.Mask)
      (net 392 "Net-(R1-Pad2)") (pintype "passive"))
  )
	(footprint "sa800u-baseboard-hw-footprints:Spacer_SMD_M2.5_H6mm_Wurth_9774060151" (layer "B.Cu")
    (tedit 61168484)
    (at 151.5 148.5)
    (property "Author" "Antmicro")
    (property "License" "Apache-2.0")
    (property "MPN" "9774060151")
    (property "Manufacturer" "Würth Elektronik")
    (property "Sheetfile" "sa800u-baseboard-hw.kicad_sch")
    (property "Sheetname" "")
    (attr smd)
    (fp_text reference "SP2" (at 0.96 -3.11 180) (layer "B.SilkS")
      (effects (font (size 0.7 0.7) (thickness 0.15)) (justify left bottom mirror))
    )
    (fp_text value "Spacer_H6mm_9774060151" (at -2.575 -4 180) (layer "B.Fab")
      (effects (font (size 0.7 0.7) (thickness 0.15)) (justify left bottom mirror))
    )
    (fp_text user "${REFERENCE}" (at -2.551 -5.25 180) (layer "B.Fab") hide
      (effects (font (size 0.7 0.7) (thickness 0.15)) (justify left bottom mirror))
    )
    (fp_text user "Author: Antmicro" (at -2.551 -6.5 180) (layer "B.Fab") hide
      (effects (font (size 0.7 0.7) (thickness 0.15)) (justify left bottom mirror))
    )
    (fp_text user "License: Apache-2.0" (at -2.551 -7.75 180) (layer "B.Fab") hide
      (effects (font (size 0.7 0.7) (thickness 0.15)) (justify left bottom mirror))
    )
    (fp_circle (center 0 0) (end 2.522481 0) (layer "B.Paste") (width 0.8) (fill none))
    (fp_circle (center -0.001 0) (end 2.548 0) (layer "B.Fab") (width 0.15) (fill none))
    (pad "1" smd circle (at 0 0) (size 6 6) (layers "B.Cu" "B.Mask")
      (net 37 "Net-(R2-Pad2)") (pintype "passive"))
    (pad "1" thru_hole circle (at -0.001 0) (size 4.1 4.1) (drill 3.7) (layers *.Cu *.Mask)
      (net 37 "Net-(R2-Pad2)") (pintype "passive"))
  )
	(footprint "sa800u-baseboard-hw-footprints:Spacer_SMD_M2.5_H6mm_Wurth_9774060151" (layer "B.Cu")
    (tedit 61168484)
    (at 64.5 148.5)
    (property "Author" "Antmicro")
    (property "License" "Apache-2.0")
    (property "MPN" "9774060151")
    (property "Manufacturer" "Würth Elektronik")
    (property "Sheetfile" "sa800u-baseboard-hw.kicad_sch")
    (property "Sheetname" "")
    (attr smd)
    (fp_text reference "SP4" (at 0.95 -3.12 180) (layer "B.SilkS")
      (effects (font (size 0.7 0.7) (thickness 0.15)) (justify left bottom mirror))
    )
    (fp_text value "Spacer_H6mm_9774060151" (at -2.575 -4 180) (layer "B.Fab")
      (effects (font (size 0.7 0.7) (thickness 0.15)) (justify left bottom mirror))
    )
    (fp_text user "Author: Antmicro" (at -2.551 -6.5 180) (layer "B.Fab") hide
      (effects (font (size 0.7 0.7) (thickness 0.15)) (justify left bottom mirror))
    )
    (fp_text user "${REFERENCE}" (at -2.551 -5.25 180) (layer "B.Fab") hide
      (effects (font (size 0.7 0.7) (thickness 0.15)) (justify left bottom mirror))
    )
    (fp_text user "License: Apache-2.0" (at -2.551 -7.75 180) (layer "B.Fab") hide
      (effects (font (size 0.7 0.7) (thickness 0.15)) (justify left bottom mirror))
    )
    (fp_circle (center 0 0) (end 2.522481 0) (layer "B.Paste") (width 0.8) (fill none))
    (fp_circle (center -0.001 0) (end 2.548 0) (layer "B.Fab") (width 0.15) (fill none))
    (pad "1" smd circle (at 0 0) (size 6 6) (layers "B.Cu" "B.Mask")
      (net 39 "Net-(R4-Pad2)") (pintype "passive"))
    (pad "1" thru_hole circle (at -0.001 0) (size 4.1 4.1) (drill 3.7) (layers *.Cu *.Mask)
      (net 39 "Net-(R4-Pad2)") (pintype "passive"))
  )
	(footprint "sa800u-baseboard-hw-footprints:Spacer_SMD_M2.5_H6mm_Wurth_9774060151" (layer "B.Cu")
    (tedit 61168484)
    (at 64.5 85.5)
    (property "Author" "Antmicro")
    (property "License" "Apache-2.0")
    (property "MPN" "9774060151")
    (property "Manufacturer" "Würth Elektronik")
    (property "Sheetfile" "sa800u-baseboard-hw.kicad_sch")
    (property "Sheetname" "")
    (attr smd)
    (fp_text reference "SP3" (at 0.86 3.89 180) (layer "B.SilkS")
      (effects (font (size 0.7 0.7) (thickness 0.15)) (justify left bottom mirror))
    )
    (fp_text value "Spacer_H6mm_9774060151" (at -2.575 -4 180) (layer "B.Fab")
      (effects (font (size 0.7 0.7) (thickness 0.15)) (justify left bottom mirror))
    )
    (fp_text user "License: Apache-2.0" (at -2.551 -7.75 180) (layer "B.Fab") hide
      (effects (font (size 0.7 0.7) (thickness 0.15)) (justify left bottom mirror))
    )
    (fp_text user "Author: Antmicro" (at -2.551 -6.5 180) (layer "B.Fab") hide
      (effects (font (size 0.7 0.7) (thickness 0.15)) (justify left bottom mirror))
    )
    (fp_text user "${REFERENCE}" (at -2.551 -5.25 180) (layer "B.Fab") hide
      (effects (font (size 0.7 0.7) (thickness 0.15)) (justify left bottom mirror))
    )
    (fp_circle (center 0 0) (end 2.522481 0) (layer "B.Paste") (width 0.8) (fill none))
    (fp_circle (center -0.001 0) (end 2.548 0) (layer "B.Fab") (width 0.15) (fill none))
    (pad "1" smd circle (at 0 0) (size 6 6) (layers "B.Cu" "B.Mask")
      (net 38 "Net-(R3-Pad2)") (pintype "passive"))
    (pad "1" thru_hole circle (at -0.001 0) (size 4.1 4.1) (drill 3.7) (layers *.Cu *.Mask)
      (net 38 "Net-(R3-Pad2)") (pintype "passive"))
  )
	(footprint "sa800u-baseboard-hw-footprints:XSON-8_1x1.95mm_P0.5mm" (layer "B.Cu")
    (tedit 5DCD5522)
    (at 133.55 107.55 90)
    (property "Author" "Antmicro")
    (property "License" "Apache-2.0")
    (property "MPN" "NTS0102GT")
    (property "Manufacturer" "NXP")
    (property "Sheetfile" "hdmi-converter.kicad_sch")
    (property "Sheetname" "HDMI converter")
    (attr smd)
    (fp_text reference "U4" (at -1.65 0.95) (layer "B.SilkS")
      (effects (font (size 0.7 0.7) (thickness 0.15)) (justify left bottom mirror))
    )
    (fp_text value "NTS0102_XSON" (at 0 -2.2 270) (layer "B.Fab")
      (effects (font (size 0.7 0.7) (thickness 0.15)) (justify left bottom mirror))
    )
    (fp_text user "Author: Antmicro" (at -0.527 -7.105 270) (layer "B.Fab") hide
      (effects (font (size 0.7 0.7) (thickness 0.15)) (justify left bottom mirror))
    )
    (fp_text user "${REFERENCE}" (at -0.527 -5.905 270) (layer "B.Fab") hide
      (effects (font (size 0.7 0.7) (thickness 0.15)) (justify left bottom mirror))
    )
    (fp_text user "License: Apache-2.0" (at -0.527 -8.306 270) (layer "B.Fab") hide
      (effects (font (size 0.7 0.7) (thickness 0.15)) (justify left bottom mirror))
    )
    (fp_line (start -0.5 1.1) (end 0.5 1.1) (layer "B.SilkS") (width 0.15))
    (fp_line (start 0.5 -1.1) (end -0.5 -1.1) (layer "B.SilkS") (width 0.15))
    (fp_circle (center -0.7 0.95) (end -0.651 0.95) (layer "B.SilkS") (width 0.15) (fill none))
    (fp_rect (start -0.8 1.2) (end 0.8 -1.2) (layer "B.CrtYd") (width 0.05) (fill none))
    (fp_line (start -0.5305 -1) (end -0.5305 1.001) (layer "B.Fab") (width 0.15))
    (fp_line (start 0.5305 1.001) (end 0.5305 -1) (layer "B.Fab") (width 0.15))
    (fp_line (start 0.5305 -1) (end -0.5305 -1) (layer "B.Fab") (width 0.15))
    (fp_line (start -0.5305 1.001) (end 0.5305 1.001) (layer "B.Fab") (width 0.15))
    (pad "1" smd rect (at -0.33 0.75 90) (size 0.5 0.31) (layers "B.Cu" "B.Paste" "B.Mask")
      (net 288 "/HDMI converter/LT9611_SDA") (pinfunction "B_{2}") (pintype "bidirectional"))
    (pad "2" smd rect (at -0.33 0.25 90) (size 0.5 0.31) (layers "B.Cu" "B.Paste" "B.Mask")
      (net 1 "GND") (pinfunction "GND") (pintype "power_in"))
    (pad "3" smd rect (at -0.33 -0.25 90) (size 0.5 0.31) (layers "B.Cu" "B.Paste" "B.Mask")
      (net 132 "VREG_S4A_1V8") (pinfunction "VCC_{A}") (pintype "power_in"))
    (pad "4" smd rect (at -0.33 -0.75 90) (size 0.5 0.31) (layers "B.Cu" "B.Paste" "B.Mask")
      (net 40 "I2C4_SDA") (pinfunction "A_{2}") (pintype "bidirectional"))
    (pad "5" smd rect (at 0.33 -0.75 270) (size 0.5 0.31) (layers "B.Cu" "B.Paste" "B.Mask")
      (net 41 "I2C4_SCL") (pinfunction "A_{1}") (pintype "bidirectional"))
    (pad "6" smd rect (at 0.33 -0.25 270) (size 0.5 0.31) (layers "B.Cu" "B.Paste" "B.Mask")
      (net 132 "VREG_S4A_1V8") (pinfunction "OE") (pintype "input"))
    (pad "7" smd rect (at 0.33 0.25 270) (size 0.5 0.31) (layers "B.Cu" "B.Paste" "B.Mask")
      (net 131 "3V3_SYS") (pinfunction "VCC_{B}") (pintype "power_in"))
    (pad "8" smd rect (at 0.33 0.75 270) (size 0.5 0.31) (layers "B.Cu" "B.Paste" "B.Mask")
      (net 287 "/HDMI converter/LT9611_SCL") (pinfunction "B_{1}") (pintype "bidirectional"))
  )
	(footprint "sa800u-baseboard-hw-footprints:Mech_M2_2280_H4mm" locked (layer "B.Cu")
    (tedit 616E8740)
    (at 66.81 100.31 -90)
    (property "Author" "Antmicro")
    (property "DNP" "DNP")
    (property "License" "Apache-2.0")
    (property "MPN" "")
    (property "Manufacturer" "")
    (property "Sheetfile" "m2.kicad_sch")
    (property "Sheetname" "M2")
    (attr exclude_from_pos_files)
    (fp_text reference "M2" (at -4.31 0.73 180) (layer "B.SilkS")
      (effects (font (size 0.7 0.7) (thickness 0.15)) (justify right bottom mirror))
    )
    (fp_text value "Mech_M2_2280_H4mm" (at 0 -6.857 90) (layer "B.Fab")
      (effects (font (size 0.7 0.7) (thickness 0.15)) (justify right bottom mirror))
    )
    (fp_text user "DNP" (at 0 0 90) (layer "B.SilkS") hide
      (effects (font (size 1 1) (thickness 0.15)) (justify mirror))
    )
    (fp_text user "Author: Antmicro" (at -12.2428 -83.1912 90) (layer "B.Fab") hide
      (effects (font (size 0.7 0.7) (thickness 0.15)) (justify left bottom mirror))
    )
    (fp_text user "License: Apache-2.0" (at -12.2428 -84.3922 90) (layer "B.Fab") hide
      (effects (font (size 0.7 0.7) (thickness 0.15)) (justify left bottom mirror))
    )
    (fp_text user "${REFERENCE}" (at -12.2428 -81.9912 90) (layer "B.Fab") hide
      (effects (font (size 0.7 0.7) (thickness 0.15)) (justify left bottom mirror))
    )
    (fp_rect (start -10.922 -0.0508) (end 11.0236 -80.0608) (layer "B.Fab") (width 0.15) (fill none))
  )
	(footprint "sa800u-baseboard-hw-footprints:Vishay_PowerPAK_1212-8_Single" (layer "B.Cu")
    (tedit 61E93346)
    (at 82.35 141 90)
    (descr "PowerPAK 1212-8 Single")
    (tags "Vishay PowerPAK 1212-8 Single")
    (property "Author" "Antmicro")
    (property "License" "Apache-2.0")
    (property "MPN" "SQS401EN-T1_BE3")
    (property "Manufacturer" "Vishay")
    (property "Sheetfile" "usb-pd.kicad_sch")
    (property "Sheetname" "USB-PD")
    (attr smd)
    (fp_text reference "Q17" (at -2.93 0.83) (layer "B.SilkS")
      (effects (font (size 0.7 0.7) (thickness 0.15)) (justify left bottom mirror))
    )
    (fp_text value "SQS401EN-T1_BE3" (at -8 -2.7 270) (layer "B.Fab")
      (effects (font (size 0.7 0.7) (thickness 0.15)) (justify left bottom mirror))
    )
    (fp_text user "License: Apache-2.0" (at -8 -7.1 270) (layer "B.Fab") hide
      (effects (font (size 0.7 0.7) (thickness 0.15)) (justify left bottom mirror))
    )
    (fp_text user "${REFERENCE}" (at -8 -4.7 270) (layer "B.Fab") hide
      (effects (font (size 0.7 0.7) (thickness 0.15)) (justify left bottom mirror))
    )
    (fp_text user "Author: Antmicro" (at -8 -5.9 270) (layer "B.Fab") hide
      (effects (font (size 0.7 0.7) (thickness 0.15)) (justify left bottom mirror))
    )
    (fp_line (start -1.651 1.651) (end -1.651 1.317) (layer "B.SilkS") (width 0.15))
    (fp_line (start -1.635 -1.634) (end 1.634 -1.634) (layer "B.SilkS") (width 0.15))
    (fp_line (start 1.634 -1.3) (end 1.634 -1.634) (layer "B.SilkS") (width 0.15))
    (fp_line (start 1.648 1.651) (end 1.648 1.317) (layer "B.SilkS") (width 0.15))
    (fp_line (start -1.635 -1.3) (end -1.635 -1.634) (layer "B.SilkS") (width 0.15))
    (fp_line (start -1.651 1.651) (end 1.648 1.651) (layer "B.SilkS") (width 0.15))
    (fp_circle (center -1.9 1.4) (end -1.85 1.4) (layer "B.SilkS") (width 0.15) (fill solid))
    (fp_rect (start -2 1.8) (end 2 -1.798) (layer "B.CrtYd") (width 0.05) (fill none))
    (fp_line (start -1.6425 1.4175) (end -1.4175 1.6425) (layer "B.Fab") (width 0.15))
    (fp_rect (start -1.651 1.651) (end 1.648 -1.648) (layer "B.Fab") (width 0.15) (fill none))
    (pad "1" smd rect (at -1.436 0.99 90) (size 0.99 0.405) (layers "B.Cu" "B.Paste" "B.Mask")
      (net 107 "/USB-PD/PD_VBUS") (pinfunction "S") (pintype "bidirectional"))
    (pad "2" smd rect (at -1.436 0.332 90) (size 0.99 0.405) (layers "B.Cu" "B.Paste" "B.Mask")
      (net 107 "/USB-PD/PD_VBUS") (pinfunction "S") (pintype "bidirectional"))
    (pad "3" smd rect (at -1.436 -0.33 90) (size 0.99 0.405) (layers "B.Cu" "B.Paste" "B.Mask")
      (net 107 "/USB-PD/PD_VBUS") (pinfunction "S") (pintype "bidirectional"))
    (pad "4" smd rect (at -1.436 -0.988 90) (size 0.99 0.405) (layers "B.Cu" "B.Paste" "B.Mask")
      (net 391 "Net-(Q17-Pad4)") (pinfunction "G") (pintype "bidirectional"))
    (pad "5" smd custom (at 0.557 0 90) (size 1.725 2.235) (layers "B.Cu" "B.Paste" "B.Mask")
      (net 142 "PD_VDD") (pinfunction "D") (pintype "bidirectional") (zone_connect 2)
      (options (clearance outline) (anchor rect))
      (primitives
        (gr_poly (pts
            (xy 0.8625 -0.1275)
            (xy 0.8625 0.1275)
            (xy 1.3725 0.1275)
            (xy 1.3725 0.5325)
            (xy 0.8625 0.5325)
            (xy 0.8625 0.7875)
            (xy 1.3725 0.7875)
            (xy 1.3725 1.195)
            (xy 0.6125 1.195)
            (xy 0.6125 -1.195)
            (xy 1.3725 -1.195)
            (xy 1.3725 -0.7875)
            (xy 0.8625 -0.7875)
            (xy 0.8625 -0.5325)
            (xy 1.3725 -0.5325)
            (xy 1.3725 -0.1275)
          ) (width 0) (fill yes))
      ))
  )
)
